# BASEBOARD_FAB2 (Tioga Pass) — schematic netlist excerpt (pin names and nets, part order shuffled) for the footprints in the layout excerpt that follows; sources: Cadence DE-HDL packaged netlist, KiCad conversion of Wiwynn_Tioga_Pass_MB.brd

R3L13  RES  49.9 1% EMPTY  pkg 0402  page 218 : A = PVCCIO_CPU0 ; B = SVID_CLK1_CPU0_R
R25W168  RES  1.00K 1% CHIP  pkg 0402  page 254 : A = JTAG_BMC_TCK0 ; B = GND
C1M4  CAP  47.0PF 50V 5% EMPTY  pkg 0402LF  page 167 : A = ISENSE_TMP421_1_DXP ; B = ISENSE_TMP421_1_DXN

(kicad_pcb
	(version 20260206)
	(generator "pcbnew")
	(generator_version "10.0")
	(general
		(thickness 1.6)
		(legacy_teardrops no)
	)
	(paper "A4")
	(title_block
		(title "Wiwynn_Tioga_Pass_MB.brd")
		(comment 1 "Tioga Pass / footprints 4563-4565 of 4770")
	)
	(layers
		(0 "F.Cu" signal "TOP")
		(4 "In1.Cu" signal "L2GND")
		(6 "In2.Cu" signal "L3")
		(8 "In3.Cu" signal "L4GND")
		(10 "In4.Cu" signal "L5")
		(12 "In5.Cu" signal "L6GND")
		(14 "In6.Cu" signal "L7VCC")
		(16 "In7.Cu" signal "L8VCC")
		(18 "In8.Cu" signal "L9GND")
		(20 "In9.Cu" signal "L10")
		(22 "In10.Cu" signal "L11GND")
		(24 "In11.Cu" signal "L12")
		(26 "In12.Cu" signal "L13GND")
		(2 "B.Cu" signal "BOTTOM")
		(9 "F.Adhes" user "F.Adhesive")
		(11 "B.Adhes" user "B.Adhesive")
		(13 "F.Paste" user "Package Geometry/Pastemask Top")
		(15 "B.Paste" user "Package Geometry/Pastemask Bottom")
		(5 "F.SilkS" user "Ref Des/Silkscreen Top")
		(7 "B.SilkS" user "Ref Des/Silkscreen Bottom")
		(1 "F.Mask" user "Board Geometry/Soldermask Top")
		(3 "B.Mask" user "Board Geometry/Soldermask Bottom")
		(17 "Dwgs.User" user "User.Drawings")
		(19 "Cmts.User" user "User.Comments")
		(21 "Eco1.User" user "User.Eco1")
		(23 "Eco2.User" user "User.Eco2")
		(25 "Edge.Cuts" user "Board Geometry/Outline")
		(27 "Margin" user)
		(31 "F.CrtYd" user "Package Geometry/Place Bound Top")
		(29 "B.CrtYd" user "Package Geometry/Place Bound Bottom")
		(35 "F.Fab" user "Ref Des/Assembly Top")
		(33 "B.Fab" user "Ref Des/Assembly Bottom")
	)
	(footprint ""
		(layer "B.Cu")
		(at 363.87024 -137.52957 90)
		(property "Reference" "R3L13"
			(at 0 0 90)
			(layer "B.SilkS")
			(hide yes)
			(effects
				(font
					(size 1.27 1.27)
				)
				(justify mirror)
			)
		)
		(property "Value" ""
			(at 0 0 90)
			(layer "B.Fab")
			(effects
				(font
					(size 1.27 1.27)
				)
				(justify mirror)
			)
		)
		(duplicate_pad_numbers_are_jumpers no)
		(fp_rect
			(start -0.2794 -0.1016)
			(end 0.2794 0.9906)
			(stroke
				(width 0)
				(type default)
			)
			(fill no)
			(layer "B.CrtYd")
		)
		(fp_line
			(start 0.2794 -0.1016)
			(end 0.2794 0.9906)
			(stroke
				(width 0.1)
				(type default)
			)
			(layer "B.Fab")
		)
		(fp_line
			(start -0.2794 -0.1016)
			(end 0.2794 -0.1016)
			(stroke
				(width 0.1)
				(type default)
			)
			(layer "B.Fab")
		)
		(fp_line
			(start 0.2794 0.9906)
			(end -0.2794 0.9906)
			(stroke
				(width 0.1)
				(type default)
			)
			(layer "B.Fab")
		)
		(fp_line
			(start -0.2794 0.9906)
			(end -0.2794 -0.1016)
			(stroke
				(width 0.1)
				(type default)
			)
			(layer "B.Fab")
		)
		(pad "1" smd rect
			(at 0 0 270)
			(size 0.508 0.508)
			(layers "B.Cu" "B.Mask" "B.Paste")
			(net "PVCCIO_CPU0")
		)
		(pad "2" smd rect
			(at 0 0.889 270)
			(size 0.508 0.508)
			(layers "B.Cu" "B.Mask" "B.Paste")
			(net "SVID_CLK1_CPU0_R")
		)
		(zone
			(layer "B.Cu")
			(hatch none 0.5)
			(connect_pads
				(clearance 0)
			)
			(min_thickness 0.25)
			(keepout
				(tracks allowed)
				(vias not_allowed)
				(pads allowed)
				(copperpour not_allowed)
				(footprints allowed)
			)
			(placement
				(enabled no)
				(sheetname "")
			)
			(fill
				(thermal_gap 0.5)
				(thermal_bridge_width 0.5)
				(island_removal_mode 0)
			)
			(polygon
				(pts
					(xy 364.12424 -137.27557) (xy 364.50524 -137.27557) (xy 364.50524 -137.78357) (xy 364.12424 -137.78357)
				)
			)
		)
		(zone
			(layer "B.Cu")
			(hatch none 0.5)
			(connect_pads
				(clearance 0)
			)
			(min_thickness 0.25)
			(keepout
				(tracks not_allowed)
				(vias allowed)
				(pads allowed)
				(copperpour not_allowed)
				(footprints allowed)
			)
			(placement
				(enabled no)
				(sheetname "")
			)
			(fill
				(thermal_gap 0.5)
				(thermal_bridge_width 0.5)
				(island_removal_mode 0)
			)
			(polygon
				(pts
					(xy 364.12424 -137.27557) (xy 364.50524 -137.27557) (xy 364.50524 -137.78357) (xy 364.12424 -137.78357)
				)
			)
		)
	)
	(footprint ""
		(layer "B.Cu")
		(at 488.50804 -123.55068)
		(property "Reference" "C1M4"
			(at 0 0 0)
			(layer "B.SilkS")
			(hide yes)
			(effects
				(font
					(size 1.27 1.27)
				)
				(justify mirror)
			)
		)
		(property "Value" ""
			(at 0 0 0)
			(layer "B.Fab")
			(effects
				(font
					(size 1.27 1.27)
				)
				(justify mirror)
			)
		)
		(duplicate_pad_numbers_are_jumpers no)
		(fp_rect
			(start 0.3048 -0.1016)
			(end -0.3048 0.9906)
			(stroke
				(width 0)
				(type default)
			)
			(fill no)
			(layer "B.CrtYd")
		)
		(fp_line
			(start -0.3048 -0.1016)
			(end 0.3048 -0.1016)
			(stroke
				(width 0.1)
				(type default)
			)
			(layer "B.Fab")
		)
		(fp_line
			(start -0.3048 0.9906)
			(end -0.3048 -0.1016)
			(stroke
				(width 0.1)
				(type default)
			)
			(layer "B.Fab")
		)
		(fp_line
			(start 0.3048 -0.1016)
			(end 0.3048 0.9906)
			(stroke
				(width 0.1)
				(type default)
			)
			(layer "B.Fab")
		)
		(fp_line
			(start 0.3048 0.9906)
			(end -0.3048 0.9906)
			(stroke
				(width 0.1)
				(type default)
			)
			(layer "B.Fab")
		)
		(pad "1" smd rect
			(at 0 0 180)
			(size 0.508 0.508)
			(layers "B.Cu" "B.Mask" "B.Paste")
			(net "ISENSE_TMP421_1_DXP")
		)
		(pad "2" smd rect
			(at 0 0.889 180)
			(size 0.508 0.508)
			(layers "B.Cu" "B.Mask" "B.Paste")
			(net "ISENSE_TMP421_1_DXN")
		)
		(zone
			(layer "B.Cu")
			(hatch none 0.5)
			(connect_pads
				(clearance 0)
			)
			(min_thickness 0.25)
			(keepout
				(tracks not_allowed)
				(vias allowed)
				(pads allowed)
				(copperpour not_allowed)
				(footprints allowed)
			)
			(placement
				(enabled no)
				(sheetname "")
			)
			(fill
				(thermal_gap 0.5)
				(thermal_bridge_width 0.5)
				(island_removal_mode 0)
			)
			(polygon
				(pts
					(xy 488.76204 -123.29668) (xy 488.25404 -123.29668) (xy 488.25404 -122.91568) (xy 488.76204 -122.91568)
				)
			)
		)
		(zone
			(layer "B.Cu")
			(hatch none 0.5)
			(connect_pads
				(clearance 0)
			)
			(min_thickness 0.25)
			(keepout
				(tracks allowed)
				(vias not_allowed)
				(pads allowed)
				(copperpour not_allowed)
				(footprints allowed)
			)
			(placement
				(enabled no)
				(sheetname "")
			)
			(fill
				(thermal_gap 0.5)
				(thermal_bridge_width 0.5)
				(island_removal_mode 0)
			)
			(polygon
				(pts
					(xy 488.76204 -123.29668) (xy 488.25404 -123.29668) (xy 488.25404 -122.91568) (xy 488.76204 -122.91568)
				)
			)
		)
	)
	(footprint ""
		(layer "B.Cu")
		(at 440.968638 -150.713186 180)
		(property "Reference" "R25W168"
			(at 0.8382 -0.67818 180)
			(unlocked yes)
			(layer "B.SilkS")
			(effects
				(font
					(size 0.4064 0.254)
					(thickness 0.1524)
				)
				(justify left mirror)
			)
		)
		(property "Value" ""
			(at 0 0 0)
			(layer "B.Fab")
			(effects
				(font
					(size 1.27 1.27)
				)
				(justify mirror)
			)
		)
		(duplicate_pad_numbers_are_jumpers no)
		(fp_poly
			(pts
				(xy 0.2794 -0.1016) (xy -0.2794 -0.1016) (xy -0.2794 0.9906) (xy 0.2794 0.9906)
			)
			(stroke
				(width 0)
				(type default)
			)
			(fill no)
			(layer "B.CrtYd")
		)
		(fp_line
			(start 0.2794 0.9906)
			(end -0.2794 0.9906)
			(stroke
				(width 0.1)
				(type default)
			)
			(layer "B.Fab")
		)
		(fp_line
			(start 0.2794 -0.1016)
			(end 0.2794 0.9906)
			(stroke
				(width 0.1)
				(type default)
			)
			(layer "B.Fab")
		)
		(fp_line
			(start -0.2794 0.9906)
			(end -0.2794 -0.1016)
			(stroke
				(width 0.1)
				(type default)
			)
			(layer "B.Fab")
		)
		(fp_line
			(start -0.2794 -0.1016)
			(end 0.2794 -0.1016)
			(stroke
				(width 0.1)
				(type default)
			)
			(layer "B.Fab")
		)
		(pad "1" smd rect
			(at 0 0)
			(size 0.508 0.508)
			(layers "B.Cu" "B.Mask" "B.Paste")
			(net "JTAG_BMC_TCK0")
		)
		(pad "2" smd rect
			(at 0 0.889)
			(size 0.508 0.508)
			(layers "B.Cu" "B.Mask" "B.Paste")
			(net "GND")
		)
		(zone
			(layer "B.Cu")
			(hatch none 0.5)
			(connect_pads
				(clearance 0)
			)
			(min_thickness 0.25)
			(keepout
				(tracks not_allowed)
				(vias allowed)
				(pads allowed)
				(copperpour not_allowed)
				(footprints allowed)
			)
			(placement
				(enabled no)
				(sheetname "")
			)
			(fill
				(thermal_gap 0.5)
				(thermal_bridge_width 0.5)
				(island_removal_mode 0)
			)
			(polygon
				(pts
					(xy 440.714638 -151.348186) (xy 441.222638 -151.348186) (xy 441.222638 -150.967186) (xy 440.714638 -150.967186)
				)
			)
		)
		(zone
			(layer "B.Cu")
			(hatch none 0.5)
			(connect_pads
				(clearance 0)
			)
			(min_thickness 0.25)
			(keepout
				(tracks allowed)
				(vias not_allowed)
				(pads allowed)
				(copperpour not_allowed)
				(footprints allowed)
			)
			(placement
				(enabled no)
				(sheetname "")
			)
			(fill
				(thermal_gap 0.5)
				(thermal_bridge_width 0.5)
				(island_removal_mode 0)
			)
			(polygon
				(pts
					(xy 440.714638 -150.967186) (xy 441.222638 -150.967186) (xy 441.222638 -151.348186) (xy 440.714638 -151.348186)
				)
			)
		)
	)
)
